(kicad_pcb
	(version 20241229)
	(generator "pcbnew")
	(generator_version "9.0")
	(general
		(thickness 1.6)
		(legacy_teardrops no)
	)
	(paper "A4")
	(title_block
		(title "environment-sensor")
		(comment 1 "footprints 53-59 of 109")
	)
	(layers
		(0 "F.Cu" signal)
		(4 "In1.Cu" signal)
		(6 "In2.Cu" signal)
		(2 "B.Cu" signal)
		(9 "F.Adhes" user "F.Adhesive")
		(11 "B.Adhes" user "B.Adhesive")
		(13 "F.Paste" user)
		(15 "B.Paste" user)
		(5 "F.SilkS" user "F.Silkscreen")
		(7 "B.SilkS" user "B.Silkscreen")
		(1 "F.Mask" user)
		(3 "B.Mask" user)
		(17 "Dwgs.User" user "User.Drawings")
		(19 "Cmts.User" user "User.Comments")
		(21 "Eco1.User" user "User.Eco1")
		(23 "Eco2.User" user "User.Eco2")
		(25 "Edge.Cuts" user)
		(27 "Margin" user)
		(31 "F.CrtYd" user "F.Courtyard")
		(29 "B.CrtYd" user "B.Courtyard")
		(35 "F.Fab" user)
		(33 "B.Fab" user)
	)
	(footprint "antmicro-footprints:C_0402_1005Metric"
		(layer "F.Cu")
		(at 201.985 130.15 -90)
		(descr "Capacitor SMD 0402")
		(tags "capacitor SMD 0402")
		(property "Reference" "C13"
			(at 0.85 -0.415 90)
			(layer "F.SilkS")
			(effects
				(font
					(size 0.7 0.7)
					(thickness 0.15)
				)
				(justify right bottom)
			)
		)
		(property "Value" "C_100n_0402"
			(at 0 1.4 90)
			(layer "F.Fab")
			(effects
				(font
					(size 0.7 0.7)
					(thickness 0.15)
				)
				(justify right bottom)
			)
		)
		(property "Description" "SMD Multilayer Ceramic Capacitor, 0.1 µF, 50 V, 0402 [1005 Metric], ± 10%, X5R, GRM Series"
			(at 0 0 270)
			(layer "F.Fab")
			(hide yes)
			(effects
				(font
					(size 1.27 1.27)
					(thickness 0.15)
				)
			)
		)
		(property "Author" "Antmicro"
			(at 71.835 332.135 0)
			(layer "F.Fab")
			(hide yes)
			(effects
				(font
					(size 1 1)
					(thickness 0.15)
				)
			)
		)
		(property "Dielectric" "X5R"
			(at 71.835 332.135 0)
			(layer "F.Fab")
			(hide yes)
			(effects
				(font
					(size 1 1)
					(thickness 0.15)
				)
			)
		)
		(property "License" "Apache-2.0"
			(at 71.835 332.135 0)
			(layer "F.Fab")
			(hide yes)
			(effects
				(font
					(size 1 1)
					(thickness 0.15)
				)
			)
		)
		(property "MPN" "GRM155R61H104KE14D"
			(at 71.835 332.135 0)
			(layer "F.Fab")
			(hide yes)
			(effects
				(font
					(size 1 1)
					(thickness 0.15)
				)
			)
		)
		(property "Manufacturer" "Murata"
			(at 71.835 332.135 0)
			(layer "F.Fab")
			(hide yes)
			(effects
				(font
					(size 1 1)
					(thickness 0.15)
				)
			)
		)
		(property "Public" "False"
			(at 71.835 332.135 0)
			(layer "F.Fab")
			(hide yes)
			(effects
				(font
					(size 1 1)
					(thickness 0.15)
				)
			)
		)
		(property "Val" "100n"
			(at 71.835 332.135 0)
			(layer "F.Fab")
			(hide yes)
			(effects
				(font
					(size 1 1)
					(thickness 0.15)
				)
			)
		)
		(property "Voltage" "50V"
			(at 71.835 332.135 0)
			(layer "F.Fab")
			(hide yes)
			(effects
				(font
					(size 1 1)
					(thickness 0.15)
				)
			)
		)
		(sheetfile "environment-sensor.kicad_sch")
		(attr smd)
		(fp_rect
			(start -0.925 -0.47)
			(end 0.925 0.47)
			(stroke
				(width 0.05)
				(type default)
			)
			(fill no)
			(layer "F.CrtYd")
		)
		(fp_line
			(start -0.494 0.248)
			(end -0.494 -0.25)
			(stroke
				(width 0.15)
				(type solid)
			)
			(layer "F.Fab")
		)
		(fp_line
			(start 0.504 0.248)
			(end -0.494 0.248)
			(stroke
				(width 0.15)
				(type solid)
			)
			(layer "F.Fab")
		)
		(fp_line
			(start -0.494 -0.25)
			(end 0.504 -0.25)
			(stroke
				(width 0.15)
				(type solid)
			)
			(layer "F.Fab")
		)
		(fp_line
			(start 0.504 -0.25)
			(end 0.504 0.248)
			(stroke
				(width 0.15)
				(type solid)
			)
			(layer "F.Fab")
		)
		(pad "1" smd roundrect
			(at -0.48 0 270)
			(size 0.59 0.64)
			(layers "F.Cu" "F.Mask" "F.Paste")
			(roundrect_rratio 0.25)
			(net 2 "+3V3")
			(pintype "passive")
		)
		(pad "2" smd roundrect
			(at 0.48 0 270)
			(size 0.59 0.64)
			(layers "F.Cu" "F.Mask" "F.Paste")
			(roundrect_rratio 0.25)
			(net 1 "GND")
			(pintype "passive")
		)
	)
	(footprint "antmicro-footprints:TP_SMD_1.5mm"
		(locked yes)
		(layer "F.Cu")
		(at 186 116)
		(property "Reference" "TP3"
			(at -1.696 -1.061 0)
			(layer "F.SilkS")
			(hide yes)
			(effects
				(font
					(size 0.7 0.7)
					(thickness 0.15)
				)
				(justify left bottom)
			)
		)
		(property "Value" "TP_1.5mm_SMD"
			(at 0 1.7 0)
			(layer "F.Fab")
			(effects
				(font
					(size 0.7 0.7)
					(thickness 0.15)
				)
				(justify left bottom)
			)
		)
		(property "Description" "test point, SMT"
			(at 0 0 0)
			(layer "F.Fab")
			(hide yes)
			(effects
				(font
					(size 1.27 1.27)
					(thickness 0.15)
				)
			)
		)
		(property "Author" "Antmicro"
			(at 0 0 0)
			(layer "F.Fab")
			(hide yes)
			(effects
				(font
					(size 1 1)
					(thickness 0.15)
				)
			)
		)
		(property "License" "Apache-2.0"
			(at 0 0 0)
			(layer "F.Fab")
			(hide yes)
			(effects
				(font
					(size 1 1)
					(thickness 0.15)
				)
			)
		)
		(property "MPN" ""
			(at 0 0 0)
			(layer "F.Fab")
			(hide yes)
			(effects
				(font
					(size 1 1)
					(thickness 0.15)
				)
			)
		)
		(property "Manufacturer" ""
			(at 0 0 0)
			(layer "F.Fab")
			(hide yes)
			(effects
				(font
					(size 1 1)
					(thickness 0.15)
				)
			)
		)
		(property "Public" "False"
			(at 0 0 0)
			(layer "F.Fab")
			(hide yes)
			(effects
				(font
					(size 1 1)
					(thickness 0.15)
				)
			)
		)
		(sheetfile "environment-sensor.kicad_sch")
		(attr exclude_from_pos_files)
		(pad "1" smd circle
			(at 0 0 270)
			(size 1.5 1.5)
			(layers "F.Cu" "F.Mask")
			(net 20 "SWDIO-JTMS")
			(pinfunction "1")
			(pintype "passive")
		)
	)
	(footprint "antmicro-footprints:C_0402_1005Metric"
		(layer "F.Cu")
		(at 182.925 133.7)
		(descr "Capacitor SMD 0402")
		(tags "capacitor SMD 0402")
		(property "Reference" "C23"
			(at 3.075 0.4 0)
			(layer "F.SilkS")
			(effects
				(font
					(size 0.7 0.7)
					(thickness 0.15)
				)
				(justify right bottom)
			)
		)
		(property "Value" "C_10p_0402"
			(at 0 1.4 0)
			(layer "F.Fab")
			(effects
				(font
					(size 0.7 0.7)
					(thickness 0.15)
				)
				(justify left bottom)
			)
		)
		(property "Description" "SMD Multilayer Ceramic Capacitor, 10 pF, 50 V, 0402 [1005 Metric], ± 2%, C0G / NP0, GCM"
			(at 0 0 0)
			(layer "F.Fab")
			(hide yes)
			(effects
				(font
					(size 1.27 1.27)
					(thickness 0.15)
				)
			)
		)
		(property "Author" "Antmicro"
			(at 0 0 0)
			(layer "F.Fab")
			(hide yes)
			(effects
				(font
					(size 1 1)
					(thickness 0.15)
				)
			)
		)
		(property "Dielectric" "C0G"
			(at 0 0 0)
			(layer "F.Fab")
			(hide yes)
			(effects
				(font
					(size 1 1)
					(thickness 0.15)
				)
			)
		)
		(property "License" "Apache-2.0"
			(at 0 0 0)
			(layer "F.Fab")
			(hide yes)
			(effects
				(font
					(size 1 1)
					(thickness 0.15)
				)
			)
		)
		(property "MPN" "GCM1555C1H100GA16D"
			(at 0 0 0)
			(layer "F.Fab")
			(hide yes)
			(effects
				(font
					(size 1 1)
					(thickness 0.15)
				)
			)
		)
		(property "Manufacturer" "Murata"
			(at 0 0 0)
			(layer "F.Fab")
			(hide yes)
			(effects
				(font
					(size 1 1)
					(thickness 0.15)
				)
			)
		)
		(property "Public" "False"
			(at 0 0 0)
			(layer "F.Fab")
			(hide yes)
			(effects
				(font
					(size 1 1)
					(thickness 0.15)
				)
			)
		)
		(property "Val" "10p"
			(at 0 0 0)
			(layer "F.Fab")
			(hide yes)
			(effects
				(font
					(size 1 1)
					(thickness 0.15)
				)
			)
		)
		(property "Voltage" "50V"
			(at 0 0 0)
			(layer "F.Fab")
			(hide yes)
			(effects
				(font
					(size 1 1)
					(thickness 0.15)
				)
			)
		)
		(sheetfile "environment-sensor.kicad_sch")
		(attr smd)
		(fp_rect
			(start -0.925 -0.47)
			(end 0.925 0.47)
			(stroke
				(width 0.05)
				(type default)
			)
			(fill no)
			(layer "F.CrtYd")
		)
		(fp_line
			(start -0.494 -0.25)
			(end 0.504 -0.25)
			(stroke
				(width 0.15)
				(type solid)
			)
			(layer "F.Fab")
		)
		(fp_line
			(start -0.494 0.248)
			(end -0.494 -0.25)
			(stroke
				(width 0.15)
				(type solid)
			)
			(layer "F.Fab")
		)
		(fp_line
			(start 0.504 -0.25)
			(end 0.504 0.248)
			(stroke
				(width 0.15)
				(type solid)
			)
			(layer "F.Fab")
		)
		(fp_line
			(start 0.504 0.248)
			(end -0.494 0.248)
			(stroke
				(width 0.15)
				(type solid)
			)
			(layer "F.Fab")
		)
		(pad "1" smd roundrect
			(at -0.48 0)
			(size 0.59 0.64)
			(layers "F.Cu" "F.Mask" "F.Paste")
			(roundrect_rratio 0.25)
			(net 1 "GND")
			(pintype "passive")
		)
		(pad "2" smd roundrect
			(at 0.48 0)
			(size 0.59 0.64)
			(layers "F.Cu" "F.Mask" "F.Paste")
			(roundrect_rratio 0.25)
			(net 33 "Net-(U3-PF0-OSC_IN)")
			(pintype "passive")
		)
	)
	(footprint "antmicro-footprints:TP_SMD_1.5mm"
		(locked yes)
		(layer "F.Cu")
		(at 188.5 116)
		(property "Reference" "TP4"
			(at -1.705 -1.138 0)
			(layer "F.SilkS")
			(hide yes)
			(effects
				(font
					(size 0.7 0.7)
					(thickness 0.15)
				)
				(justify left bottom)
			)
		)
		(property "Value" "TP_1.5mm_SMD"
			(at 0 1.7 0)
			(layer "F.Fab")
			(effects
				(font
					(size 0.7 0.7)
					(thickness 0.15)
				)
				(justify left bottom)
			)
		)
		(property "Description" "test point, SMT"
			(at 0 0 0)
			(layer "F.Fab")
			(hide yes)
			(effects
				(font
					(size 1.27 1.27)
					(thickness 0.15)
				)
			)
		)
		(property "Author" "Antmicro"
			(at 0 0 0)
			(layer "F.Fab")
			(hide yes)
			(effects
				(font
					(size 1 1)
					(thickness 0.15)
				)
			)
		)
		(property "License" "Apache-2.0"
			(at 0 0 0)
			(layer "F.Fab")
			(hide yes)
			(effects
				(font
					(size 1 1)
					(thickness 0.15)
				)
			)
		)
		(property "MPN" ""
			(at 0 0 0)
			(layer "F.Fab")
			(hide yes)
			(effects
				(font
					(size 1 1)
					(thickness 0.15)
				)
			)
		)
		(property "Manufacturer" ""
			(at 0 0 0)
			(layer "F.Fab")
			(hide yes)
			(effects
				(font
					(size 1 1)
					(thickness 0.15)
				)
			)
		)
		(property "Public" "False"
			(at 0 0 0)
			(layer "F.Fab")
			(hide yes)
			(effects
				(font
					(size 1 1)
					(thickness 0.15)
				)
			)
		)
		(sheetfile "environment-sensor.kicad_sch")
		(attr exclude_from_pos_files)
		(pad "1" smd circle
			(at 0 0 270)
			(size 1.5 1.5)
			(layers "F.Cu" "F.Mask")
			(net 18 "SWCLK-JTCK")
			(pinfunction "1")
			(pintype "passive")
		)
	)
	(footprint "antmicro-footprints:C_0402_1005Metric"
		(layer "F.Cu")
		(at 178.524 115.223 180)
		(descr "Capacitor SMD 0402")
		(tags "capacitor SMD 0402")
		(property "Reference" "C6"
			(at 0.054 0.546 0)
			(layer "F.SilkS")
			(effects
				(font
					(size 0.7 0.7)
					(thickness 0.15)
				)
				(justify right bottom)
			)
		)
		(property "Value" "C_100n_0402"
			(at 0 1.4 0)
			(layer "F.Fab")
			(effects
				(font
					(size 0.7 0.7)
					(thickness 0.15)
				)
				(justify right bottom)
			)
		)
		(property "Description" "SMD Multilayer Ceramic Capacitor, 0.1 µF, 50 V, 0402 [1005 Metric], ± 10%, X5R, GRM Series"
			(at 0 0 180)
			(layer "F.Fab")
			(hide yes)
			(effects
				(font
					(size 1.27 1.27)
					(thickness 0.15)
				)
			)
		)
		(property "Author" "Antmicro"
			(at 357.048 230.446 0)
			(layer "F.Fab")
			(hide yes)
			(effects
				(font
					(size 1 1)
					(thickness 0.15)
				)
			)
		)
		(property "Dielectric" "X5R"
			(at 357.048 230.446 0)
			(layer "F.Fab")
			(hide yes)
			(effects
				(font
					(size 1 1)
					(thickness 0.15)
				)
			)
		)
		(property "License" "Apache-2.0"
			(at 357.048 230.446 0)
			(layer "F.Fab")
			(hide yes)
			(effects
				(font
					(size 1 1)
					(thickness 0.15)
				)
			)
		)
		(property "MPN" "GRM155R61H104KE14D"
			(at 357.048 230.446 0)
			(layer "F.Fab")
			(hide yes)
			(effects
				(font
					(size 1 1)
					(thickness 0.15)
				)
			)
		)
		(property "Manufacturer" "Murata"
			(at 357.048 230.446 0)
			(layer "F.Fab")
			(hide yes)
			(effects
				(font
					(size 1 1)
					(thickness 0.15)
				)
			)
		)
		(property "Public" "False"
			(at 357.048 230.446 0)
			(layer "F.Fab")
			(hide yes)
			(effects
				(font
					(size 1 1)
					(thickness 0.15)
				)
			)
		)
		(property "Val" "100n"
			(at 357.048 230.446 0)
			(layer "F.Fab")
			(hide yes)
			(effects
				(font
					(size 1 1)
					(thickness 0.15)
				)
			)
		)
		(property "Voltage" "50V"
			(at 357.048 230.446 0)
			(layer "F.Fab")
			(hide yes)
			(effects
				(font
					(size 1 1)
					(thickness 0.15)
				)
			)
		)
		(sheetfile "environment-sensor.kicad_sch")
		(attr smd)
		(fp_rect
			(start -0.925 -0.47)
			(end 0.925 0.47)
			(stroke
				(width 0.05)
				(type default)
			)
			(fill no)
			(layer "F.CrtYd")
		)
		(fp_line
			(start 0.504 0.248)
			(end -0.494 0.248)
			(stroke
				(width 0.15)
				(type solid)
			)
			(layer "F.Fab")
		)
		(fp_line
			(start 0.504 -0.25)
			(end 0.504 0.248)
			(stroke
				(width 0.15)
				(type solid)
			)
			(layer "F.Fab")
		)
		(fp_line
			(start -0.494 0.248)
			(end -0.494 -0.25)
			(stroke
				(width 0.15)
				(type solid)
			)
			(layer "F.Fab")
		)
		(fp_line
			(start -0.494 -0.25)
			(end 0.504 -0.25)
			(stroke
				(width 0.15)
				(type solid)
			)
			(layer "F.Fab")
		)
		(pad "1" smd roundrect
			(at -0.48 0 180)
			(size 0.59 0.64)
			(layers "F.Cu" "F.Mask" "F.Paste")
			(roundrect_rratio 0.25)
			(net 1 "GND")
			(pintype "passive")
		)
		(pad "2" smd roundrect
			(at 0.48 0 180)
			(size 0.59 0.64)
			(layers "F.Cu" "F.Mask" "F.Paste")
			(roundrect_rratio 0.25)
			(net 29 "Net-(U1-3V3OUT)")
			(pintype "passive")
		)
	)
	(footprint "antmicro-footprints:SOD-923"
		(layer "F.Cu")
		(at 169.985 128.45)
		(property "Reference" "D4"
			(at 1.315 -0.007 0)
			(unlocked yes)
			(layer "F.SilkS")
			(effects
				(font
					(size 0.65 0.65)
					(thickness 0.15)
				)
			)
		)
		(property "Value" "ESD9X5.0ST5G"
			(at 0 2.4 0)
			(unlocked yes)
			(layer "F.Fab")
			(effects
				(font
					(size 1 1)
					(thickness 0.15)
				)
			)
		)
		(property "Description" "Unidirectional TVS, 30 kV,  SOD-923, 5 V, 65 pF"
			(at 0 0 0)
			(layer "F.Fab")
			(hide yes)
			(effects
				(font
					(size 1.27 1.27)
					(thickness 0.15)
				)
			)
		)
		(property "Author" "Antmicro"
			(at 0 0 0)
			(layer "F.Fab")
			(hide yes)
			(effects
				(font
					(size 1 1)
					(thickness 0.15)
				)
			)
		)
		(property "License" "Apache-2.0"
			(at 0 0 0)
			(layer "F.Fab")
			(hide yes)
			(effects
				(font
					(size 1 1)
					(thickness 0.15)
				)
			)
		)
		(property "MPN" "ESD9X5.0ST5G"
			(at 0 0 0)
			(layer "F.Fab")
			(hide yes)
			(effects
				(font
					(size 1 1)
					(thickness 0.15)
				)
			)
		)
		(property "Manufacturer" "ON Semiconductor"
			(at 0 0 0)
			(layer "F.Fab")
			(hide yes)
			(effects
				(font
					(size 1 1)
					(thickness 0.15)
				)
			)
		)
		(property "Public" "False"
			(at 0 0 0)
			(layer "F.Fab")
			(hide yes)
			(effects
				(font
					(size 1 1)
					(thickness 0.15)
				)
			)
		)
		(sheetfile "environment-sensor.kicad_sch")
		(attr smd)
		(fp_line
			(start -0.5 -0.4)
			(end 0.5 -0.4)
			(stroke
				(width 0.15)
				(type solid)
			)
			(layer "F.SilkS")
		)
		(fp_line
			(start -0.5 -0.3)
			(end -0.5 -0.4)
			(stroke
				(width 0.15)
				(type solid)
			)
			(layer "F.SilkS")
		)
		(fp_line
			(start -0.5 0.4)
			(end -0.5 0.3)
			(stroke
				(width 0.15)
				(type solid)
			)
			(layer "F.SilkS")
		)
		(fp_line
			(start -0.5 0.4)
			(end 0.5 0.4)
			(stroke
				(width 0.15)
				(type solid)
			)
			(layer "F.SilkS")
		)
		(fp_line
			(start -0.16 -0.4)
			(end -0.16 0.4)
			(stroke
				(width 0.15)
				(type solid)
			)
			(layer "F.SilkS")
		)
		(fp_line
			(start 0.5 -0.4)
			(end 0.5 -0.3)
			(stroke
				(width 0.15)
				(type solid)
			)
			(layer "F.SilkS")
		)
		(fp_line
			(start 0.5 0.4)
			(end 0.5 0.3)
			(stroke
				(width 0.15)
				(type solid)
			)
			(layer "F.SilkS")
		)
		(fp_rect
			(start -0.68 -0.41)
			(end 0.68 0.41)
			(stroke
				(width 0.05)
				(type solid)
			)
			(fill no)
			(layer "F.CrtYd")
		)
		(fp_line
			(start -0.202 -0.3)
			(end -0.202 0.298)
			(stroke
				(width 0.15)
				(type solid)
			)
			(layer "F.Fab")
		)
		(fp_rect
			(start -0.402 -0.3)
			(end 0.4 0.298)
			(stroke
				(width 0.15)
				(type solid)
			)
			(fill no)
			(layer "F.Fab")
		)
		(fp_text user "${REFERENCE}"
			(at 0 1.1 0)
			(unlocked yes)
			(layer "F.Fab")
			(effects
				(font
					(size 1 1)
					(thickness 0.15)
				)
			)
		)
		(pad "1" smd roundrect
			(at -0.438 0)
			(size 0.4 0.325)
			(layers "F.Cu" "F.Mask" "F.Paste")
			(roundrect_rratio 0.25)
			(net 1 "GND")
			(pinfunction "C")
			(pintype "passive")
		)
		(pad "2" smd roundrect
			(at 0.436 0)
			(size 0.4 0.325)
			(layers "F.Cu" "F.Mask" "F.Paste")
			(roundrect_rratio 0.25)
			(net 5 "/USB_CC2")
			(pinfunction "A")
			(pintype "passive")
		)
	)
	(footprint "antmicro-footprints:SOD-923"
		(layer "F.Cu")
		(at 169.985 125.05)
		(property "Reference" "D3"
			(at 1.315 0 0)
			(unlocked yes)
			(layer "F.SilkS")
			(effects
				(font
					(size 0.65 0.65)
					(thickness 0.15)
				)
			)
		)
		(property "Value" "ESD9X5.0ST5G"
			(at 0 2.4 0)
			(unlocked yes)
			(layer "F.Fab")
			(effects
				(font
					(size 1 1)
					(thickness 0.15)
				)
			)
		)
		(property "Description" "Unidirectional TVS, 30 kV,  SOD-923, 5 V, 65 pF"
			(at 0 0 0)
			(layer "F.Fab")
			(hide yes)
			(effects
				(font
					(size 1.27 1.27)
					(thickness 0.15)
				)
			)
		)
		(property "Author" "Antmicro"
			(at 0 0 0)
			(layer "F.Fab")
			(hide yes)
			(effects
				(font
					(size 1 1)
					(thickness 0.15)
				)
			)
		)
		(property "License" "Apache-2.0"
			(at 0 0 0)
			(layer "F.Fab")
			(hide yes)
			(effects
				(font
					(size 1 1)
					(thickness 0.15)
				)
			)
		)
		(property "MPN" "ESD9X5.0ST5G"
			(at 0 0 0)
			(layer "F.Fab")
			(hide yes)
			(effects
				(font
					(size 1 1)
					(thickness 0.15)
				)
			)
		)
		(property "Manufacturer" "ON Semiconductor"
			(at 0 0 0)
			(layer "F.Fab")
			(hide yes)
			(effects
				(font
					(size 1 1)
					(thickness 0.15)
				)
			)
		)
		(property "Public" "False"
			(at 0 0 0)
			(layer "F.Fab")
			(hide yes)
			(effects
				(font
					(size 1 1)
					(thickness 0.15)
				)
			)
		)
		(sheetfile "environment-sensor.kicad_sch")
		(attr smd)
		(fp_line
			(start -0.5 -0.4)
			(end 0.5 -0.4)
			(stroke
				(width 0.15)
				(type solid)
			)
			(layer "F.SilkS")
		)
		(fp_line
			(start -0.5 -0.3)
			(end -0.5 -0.4)
			(stroke
				(width 0.15)
				(type solid)
			)
			(layer "F.SilkS")
		)
		(fp_line
			(start -0.5 0.4)
			(end -0.5 0.3)
			(stroke
				(width 0.15)
				(type solid)
			)
			(layer "F.SilkS")
		)
		(fp_line
			(start -0.5 0.4)
			(end 0.5 0.4)
			(stroke
				(width 0.15)
				(type solid)
			)
			(layer "F.SilkS")
		)
		(fp_line
			(start -0.16 -0.4)
			(end -0.16 0.4)
			(stroke
				(width 0.15)
				(type solid)
			)
			(layer "F.SilkS")
		)
		(fp_line
			(start 0.5 -0.4)
			(end 0.5 -0.3)
			(stroke
				(width 0.15)
				(type solid)
			)
			(layer "F.SilkS")
		)
		(fp_line
			(start 0.5 0.4)
			(end 0.5 0.3)
			(stroke
				(width 0.15)
				(type solid)
			)
			(layer "F.SilkS")
		)
		(fp_rect
			(start -0.68 -0.41)
			(end 0.68 0.41)
			(stroke
				(width 0.05)
				(type solid)
			)
			(fill no)
			(layer "F.CrtYd")
		)
		(fp_line
			(start -0.202 -0.3)
			(end -0.202 0.298)
			(stroke
				(width 0.15)
				(type solid)
			)
			(layer "F.Fab")
		)
		(fp_rect
			(start -0.402 -0.3)
			(end 0.4 0.298)
			(stroke
				(width 0.15)
				(type solid)
			)
			(fill no)
			(layer "F.Fab")
		)
		(fp_text user "${REFERENCE}"
			(at 0 1.1 0)
			(unlocked yes)
			(layer "F.Fab")
			(effects
				(font
					(size 1 1)
					(thickness 0.15)
				)
			)
		)
		(pad "1" smd roundrect
			(at -0.438 0)
			(size 0.4 0.325)
			(layers "F.Cu" "F.Mask" "F.Paste")
			(roundrect_rratio 0.25)
			(net 1 "GND")
			(pinfunction "C")
			(pintype "passive")
		)
		(pad "2" smd roundrect
			(at 0.436 0)
			(size 0.4 0.325)
			(layers "F.Cu" "F.Mask" "F.Paste")
			(roundrect_rratio 0.25)
			(net 4 "/USB_CC1")
			(pinfunction "A")
			(pintype "passive")
		)
	)
)
